# T6G (Grand Teton) — schematic netlist excerpt (pin names and nets, part order shuffled) for the footprints in the layout excerpt that follows; sources: Cadence DE-HDL packaged netlist, KiCad conversion of 04192023_DAF0TMB3IC0_F0TG_MB_C_brd_V02_OCP.brd

TP12  TP  NA  pkg TP  page 54 : TP = VSENSE_VSS_SENSE_B_P1
PR6008  Q_RES  10K 1% CHIP  pkg 0402LF  page 270 : A = P1V2_AUX_FB ; B = P1V2_AUX
R1479  Q_RES  4.7K 5% EMPTY  pkg 0201LF  page 298 : A = P1V8_CPU0_RT_1D ; B = JTAG_TCK_RT_CPU0_P2
C910  Q_CAP_DIFFBUS  DIFF BUS_0.22UF 6.3V 20% X6S  pkg C0201  page 63 : \1\ = P5E_CPU0_P0_TX_C_DN<11> ; \2\ = P5E_CPU0_P0_TX_DN<11>

(kicad_pcb
	(version 20260206)
	(generator "pcbnew")
	(generator_version "10.0")
	(general
		(thickness 1.6)
		(legacy_teardrops no)
	)
	(paper "A4")
	(title_block
		(title "04192023_DAF0TMB3IC0_F0TG_MB_C_brd_V02_OCP.brd")
		(comment 1 "Grand Teton / footprints 2264-2267 of 8354")
	)
	(layers
		(0 "F.Cu" signal "TOP")
		(4 "In1.Cu" signal "GND")
		(6 "In2.Cu" signal "IN1")
		(8 "In3.Cu" signal "GND1")
		(10 "In4.Cu" signal "IN2")
		(12 "In5.Cu" signal "GND2")
		(14 "In6.Cu" signal "IN3")
		(16 "In7.Cu" signal "GND3")
		(18 "In8.Cu" signal "VCC")
		(20 "In9.Cu" signal "VCC1")
		(22 "In10.Cu" signal "GND4")
		(24 "In11.Cu" signal "IN4")
		(26 "In12.Cu" signal "GND5")
		(28 "In13.Cu" signal "IN5")
		(30 "In14.Cu" signal "GND6")
		(32 "In15.Cu" signal "IN6")
		(34 "In16.Cu" signal "GND7")
		(2 "B.Cu" signal "BOTTOM")
		(9 "F.Adhes" user "F.Adhesive")
		(11 "B.Adhes" user "B.Adhesive")
		(13 "F.Paste" user "Package Geometry/Pastemask Top")
		(15 "B.Paste" user "Package Geometry/Pastemask Bottom")
		(5 "F.SilkS" user "Ref Des/Silkscreen Top")
		(7 "B.SilkS" user "Ref Des/Silkscreen Bottom")
		(1 "F.Mask" user "Board Geometry/Soldermask Top")
		(3 "B.Mask" user "Board Geometry/Soldermask Bottom")
		(17 "Dwgs.User" user "User.Drawings")
		(19 "Cmts.User" user "User.Comments")
		(21 "Eco1.User" user "User.Eco1")
		(23 "Eco2.User" user "User.Eco2")
		(25 "Edge.Cuts" user "Board Geometry/Outline")
		(27 "Margin" user)
		(31 "F.CrtYd" user "Package Geometry/Place Bound Top")
		(29 "B.CrtYd" user "Package Geometry/Place Bound Bottom")
		(35 "F.Fab" user "Ref Des/Assembly Top")
		(33 "B.Fab" user "Ref Des/Assembly Bottom")
	)
	(footprint ""
		(layer "F.Cu")
		(at 120.631712 -71.337932)
		(property "Reference" "PR6008"
			(at 0 0 0)
			(layer "F.SilkS")
			(hide yes)
			(effects
				(font
					(size 1.27 1.27)
				)
			)
		)
		(property "Value" ""
			(at 0 0 0)
			(layer "F.Fab")
			(effects
				(font
					(size 1.27 1.27)
				)
			)
		)
		(duplicate_pad_numbers_are_jumpers no)
		(fp_line
			(start -0.7874 -0.4064)
			(end 0.7874 -0.4064)
			(stroke
				(width 0.1524)
				(type default)
			)
			(layer "F.SilkS")
		)
		(fp_line
			(start -0.7874 0.4064)
			(end -0.7874 -0.4064)
			(stroke
				(width 0.1524)
				(type default)
			)
			(layer "F.SilkS")
		)
		(fp_line
			(start 0.7874 -0.4064)
			(end 0.7874 0.4064)
			(stroke
				(width 0.1524)
				(type default)
			)
			(layer "F.SilkS")
		)
		(fp_line
			(start 0.7874 0.4064)
			(end -0.7874 0.4064)
			(stroke
				(width 0.1524)
				(type default)
			)
			(layer "F.SilkS")
		)
		(fp_line
			(start -0.67945 -0.305054)
			(end -0.12065 -0.305054)
			(stroke
				(width 0.1)
				(type default)
			)
			(layer "F.Fab")
		)
		(fp_line
			(start -0.67945 0.3048)
			(end -0.67945 -0.305054)
			(stroke
				(width 0.1)
				(type default)
			)
			(layer "F.Fab")
		)
		(fp_line
			(start -0.12065 -0.305054)
			(end -0.12065 -0.2794)
			(stroke
				(width 0.1)
				(type default)
			)
			(layer "F.Fab")
		)
		(fp_line
			(start -0.12065 -0.2794)
			(end 0.12065 -0.2794)
			(stroke
				(width 0.1)
				(type default)
			)
			(layer "F.Fab")
		)
		(fp_line
			(start -0.12065 0.2794)
			(end -0.12065 0.3048)
			(stroke
				(width 0.1)
				(type default)
			)
			(layer "F.Fab")
		)
		(fp_line
			(start -0.12065 0.3048)
			(end -0.67945 0.3048)
			(stroke
				(width 0.1)
				(type default)
			)
			(layer "F.Fab")
		)
		(fp_line
			(start 0.120396 0.2794)
			(end -0.12065 0.2794)
			(stroke
				(width 0.1)
				(type default)
			)
			(layer "F.Fab")
		)
		(fp_line
			(start 0.120396 0.3048)
			(end 0.120396 0.2794)
			(stroke
				(width 0.1)
				(type default)
			)
			(layer "F.Fab")
		)
		(fp_line
			(start 0.12065 -0.3048)
			(end 0.67945 -0.3048)
			(stroke
				(width 0.1)
				(type default)
			)
			(layer "F.Fab")
		)
		(fp_line
			(start 0.12065 -0.2794)
			(end 0.12065 -0.3048)
			(stroke
				(width 0.1)
				(type default)
			)
			(layer "F.Fab")
		)
		(fp_line
			(start 0.67945 -0.3048)
			(end 0.67945 0.3048)
			(stroke
				(width 0.1)
				(type default)
			)
			(layer "F.Fab")
		)
		(fp_line
			(start 0.67945 0.3048)
			(end 0.120396 0.3048)
			(stroke
				(width 0.1)
				(type default)
			)
			(layer "F.Fab")
		)
		(pad "1" smd circle
			(at -0.40005 0)
			(size 0 0)
			(layers "F.Cu" "F.Mask" "F.Paste")
			(net "P1V2_AUX_FB")
		)
		(pad "2" smd circle
			(at 0.40005 0)
			(size 0 0)
			(layers "F.Cu" "F.Mask" "F.Paste")
			(net "P1V2_AUX")
		)
	)
	(footprint ""
		(layer "F.Cu")
		(at 432.308 -408.2796)
		(property "Reference" "R1479"
			(at 0 0 0)
			(layer "F.SilkS")
			(hide yes)
			(effects
				(font
					(size 1.27 1.27)
				)
			)
		)
		(property "Value" ""
			(at 0 0 0)
			(layer "F.Fab")
			(effects
				(font
					(size 1.27 1.27)
				)
			)
		)
		(duplicate_pad_numbers_are_jumpers no)
		(fp_line
			(start -0.32512 -0.175006)
			(end 0.32512 -0.175006)
			(stroke
				(width 0.1)
				(type default)
			)
			(layer "F.Fab")
		)
		(fp_line
			(start -0.32512 0.175006)
			(end -0.32512 -0.175006)
			(stroke
				(width 0.1)
				(type default)
			)
			(layer "F.Fab")
		)
		(fp_line
			(start 0.32512 -0.175006)
			(end 0.32512 0.175006)
			(stroke
				(width 0.1)
				(type default)
			)
			(layer "F.Fab")
		)
		(fp_line
			(start 0.32512 0.175006)
			(end -0.32512 0.175006)
			(stroke
				(width 0.1)
				(type default)
			)
			(layer "F.Fab")
		)
		(pad "1" smd rect
			(at -0.2667 0)
			(size 0.3048 0.381)
			(layers "F.Cu" "F.Mask" "F.Paste")
			(net "P1V8_CPU0_RT_1D")
		)
		(pad "2" smd rect
			(at 0.2667 0 180)
			(size 0.3048 0.381)
			(layers "F.Cu" "F.Mask" "F.Paste")
			(net "JTAG_TCK_RT_CPU0_P2")
		)
	)
	(footprint ""
		(layer "F.Cu")
		(at 320.325496 -381.41783 -90)
		(property "Reference" "C910"
			(at 0 0 270)
			(layer "F.SilkS")
			(hide yes)
			(effects
				(font
					(size 1.27 1.27)
				)
			)
		)
		(property "Value" ""
			(at 0 0 270)
			(layer "F.Fab")
			(effects
				(font
					(size 1.27 1.27)
				)
			)
		)
		(duplicate_pad_numbers_are_jumpers no)
		(fp_line
			(start -0.299974 0.150114)
			(end -0.299974 -0.150114)
			(stroke
				(width 0.1)
				(type default)
			)
			(layer "F.Fab")
		)
		(fp_line
			(start 0.299974 0.150114)
			(end -0.299974 0.150114)
			(stroke
				(width 0.1)
				(type default)
			)
			(layer "F.Fab")
		)
		(fp_line
			(start -0.299974 -0.150114)
			(end 0.299974 -0.150114)
			(stroke
				(width 0.1)
				(type default)
			)
			(layer "F.Fab")
		)
		(fp_line
			(start 0.299974 -0.150114)
			(end 0.299974 0.150114)
			(stroke
				(width 0.1)
				(type default)
			)
			(layer "F.Fab")
		)
		(pad "1" smd rect
			(at -0.2667 0 270)
			(size 0.3048 0.381)
			(layers "F.Cu" "F.Mask" "F.Paste")
			(net "P5E_CPU0_P0_TX_C_DN<11>")
		)
		(pad "2" smd rect
			(at 0.2667 0 270)
			(size 0.3048 0.381)
			(layers "F.Cu" "F.Mask" "F.Paste")
			(net "P5E_CPU0_P0_TX_DN<11>")
		)
	)
	(footprint ""
		(layer "F.Cu")
		(at 20.00504 -333.295244 180)
		(property "Reference" "TP12"
			(at 6.88848 0.856742 0)
			(unlocked yes)
			(layer "F.SilkS")
			(effects
				(font
					(size 0.7874 0.5842)
					(thickness 0.1524)
				)
				(justify left)
			)
		)
		(property "Value" ""
			(at 0 0 180)
			(layer "F.Fab")
			(effects
				(font
					(size 1.27 1.27)
				)
			)
		)
		(duplicate_pad_numbers_are_jumpers no)
		(pad "1" smd circle
			(at 0 0 180)
			(size 0.762 0.762)
			(layers "F.Cu" "F.Mask" "F.Paste")
			(net "VSENSE_VSS_SENSE_B_P1")
		)
	)
)
